G04*
G04 #@! TF.GenerationSoftware,Altium Limited,Altium Designer,22.4.2 (48)*
G04*
G04 Layer_Color=128*
%FSLAX25Y25*%
%MOIN*%
G70*
G04*
G04 #@! TF.SameCoordinates,B69760C6-9901-4916-8BAC-4CFDAA04743E*
G04*
G04*
G04 #@! TF.FilePolarity,Positive*
G04*
G01*
G75*
M02*
